#ISCELL
  mstr_misc dns *
  *
#ISCELL
  pure_quanta quanta_title_block_c *
  *
#ISCELL
  pure_quanta_power universal_power *
  page255_i11
#ISCELL
  pure_quanta_power universal_gnd *
  page255_i12
#CELL
  pure_quanta q_cap *
  page255_i13
#CELL
  pure_quanta 74lvc2g07dw7 *
  page255_i16
#ISCELL
  pure_quanta_power universal_gnd *
  page255_i17
#ISCELL
  pure_quanta_power universal_power *
  page255_i28
#ISCELL
  pure_quanta_power universal_gnd *
  page255_i30
#CELL
  pure_quanta q_res *
  page255_i31
#ISCELL
  standard offpage *
  page255_i32
#CELL
  pure_quanta q_res *
  page255_i33
#ISCELL
  pure_quanta_power universal_power *
  page255_i34
#CELL
  pure_quanta q_res *
  page255_i35
#ISCELL
  standard offpage *
  page255_i36
#CELL
  pure_quanta q_res *
  page255_i37
#ISCELL
  pure_quanta_power universal_gnd *
  page255_i38
#ISCELL
  pure_quanta_power universal_power *
  page255_i39
#CELL
  pure_quanta q_res *
  page255_i40
#ISCELL
  standard offpage *
  page255_i41
#CELL
  pure_quanta q_res *
  page255_i42
#ISCELL
  pure_quanta_power universal_gnd *
  page255_i43
#ISCELL
  standard offpage *
  page255_i44
#CELL
  pure_quanta q_res *
  page255_i45
#ISCELL
  pure_quanta_power universal_power *
  page255_i46
#CELL
  pure_quanta q_res *
  page255_i47
#CELL
  pure_quanta q_res *
  page255_i48
#ISCELL
  pure_quanta_power universal_gnd *
  page255_i49
#CELL
  pure_quanta 74lvc2g07dw7 *
  page255_i50
#ISCELL
  standard offpage *
  page255_i51
#CELL
  pure_quanta q_res *
  page255_i53
#ISCELL
  pure_quanta_power universal_power *
  page255_i54
#CELL
  pure_quanta q_res *
  page255_i55
#ISCELL
  pure_quanta_power universal_power *
  page255_i56
#CELL
  pure_quanta q_res *
  page255_i57
#ISCELL
  standard offpage *
  page255_i58
#CELL
  pure_quanta q_res *
  page255_i62
#ISCELL
  pure_quanta_power universal_gnd *
  page255_i63
#ISCELL
  pure_quanta_power universal_power *
  page255_i66
#CELL
  pure_quanta q_cap *
  page255_i67
#ISCELL
  pure_quanta_power universal_gnd *
  page255_i68
#ISCELL
  pure_quanta_power universal_gnd *
  page255_i69
#CELL
  pure_quanta q_res *
  page255_i70
#ISCELL
  pure_quanta_power universal_gnd *
  page255_i74
#CELL
  pure_quanta q_res *
  page255_i75
